(kicad_pcb
	(version 20260206)
	(generator "pcbnew")
	(generator_version "10.0")
	(general
		(thickness 1.6)
		(legacy_teardrops no)
	)
	(paper "A4")
	(title_block
		(title "03242023_DA0F0TMBIJ0_F0T_Motherboard_J_brd_V01_OCP.brd")
		(comment 1 "Grand Teton / footprints 5342-5347 of 6105")
	)
	(layers
		(0 "F.Cu" signal "TOP")
		(4 "In1.Cu" signal "GND")
		(6 "In2.Cu" signal "IN1")
		(8 "In3.Cu" signal "GND1")
		(10 "In4.Cu" signal "IN2")
		(12 "In5.Cu" signal "GND2")
		(14 "In6.Cu" signal "IN3")
		(16 "In7.Cu" signal "GND3")
		(18 "In8.Cu" signal "VCC")
		(20 "In9.Cu" signal "VCC1")
		(22 "In10.Cu" signal "GND4")
		(24 "In11.Cu" signal "IN4")
		(26 "In12.Cu" signal "GND5")
		(28 "In13.Cu" signal "IN5")
		(30 "In14.Cu" signal "GND6")
		(32 "In15.Cu" signal "IN6")
		(34 "In16.Cu" signal "GND7")
		(2 "B.Cu" signal "BOTTOM")
		(9 "F.Adhes" user "F.Adhesive")
		(11 "B.Adhes" user "B.Adhesive")
		(13 "F.Paste" user "Package Geometry/Pastemask Top")
		(15 "B.Paste" user "Package Geometry/Pastemask Bottom")
		(5 "F.SilkS" user "Ref Des/Silkscreen Top")
		(7 "B.SilkS" user "Ref Des/Silkscreen Bottom")
		(1 "F.Mask" user "Board Geometry/Soldermask Top")
		(3 "B.Mask" user "Board Geometry/Soldermask Bottom")
		(17 "Dwgs.User" user "User.Drawings")
		(19 "Cmts.User" user "User.Comments")
		(21 "Eco1.User" user "User.Eco1")
		(23 "Eco2.User" user "User.Eco2")
		(25 "Edge.Cuts" user "Board Geometry/Outline")
		(27 "Margin" user)
		(31 "F.CrtYd" user "Package Geometry/Place Bound Top")
		(29 "B.CrtYd" user "Package Geometry/Place Bound Bottom")
		(35 "F.Fab" user "Ref Des/Assembly Top")
		(33 "B.Fab" user "Ref Des/Assembly Bottom")
	)
	(footprint ""
		(layer "B.Cu")
		(at 182.68188 -101.564948 180)
		(property "Reference" "R3344"
			(at 0 0 0)
			(layer "B.SilkS")
			(hide yes)
			(effects
				(font
					(size 1.27 1.27)
				)
				(justify mirror)
			)
		)
		(property "Value" ""
			(at 0 0 0)
			(layer "B.Fab")
			(effects
				(font
					(size 1.27 1.27)
				)
				(justify mirror)
			)
		)
		(duplicate_pad_numbers_are_jumpers no)
		(fp_line
			(start 1.2954 0.5842)
			(end 1.2954 -0.5842)
			(stroke
				(width 0.1524)
				(type default)
			)
			(layer "B.SilkS")
		)
		(fp_line
			(start 1.2954 -0.5842)
			(end -1.2954 -0.5842)
			(stroke
				(width 0.1524)
				(type default)
			)
			(layer "B.SilkS")
		)
		(fp_line
			(start -1.2954 0.5842)
			(end 1.2954 0.5842)
			(stroke
				(width 0.1524)
				(type default)
			)
			(layer "B.SilkS")
		)
		(fp_line
			(start -1.2954 -0.5842)
			(end -1.2954 0.5842)
			(stroke
				(width 0.1524)
				(type default)
			)
			(layer "B.SilkS")
		)
		(fp_line
			(start 1.1938 0.4064)
			(end 1.1938 -0.406654)
			(stroke
				(width 0.1)
				(type default)
			)
			(layer "B.Fab")
		)
		(fp_line
			(start 1.1938 -0.406654)
			(end 0.8636 -0.406654)
			(stroke
				(width 0.1)
				(type default)
			)
			(layer "B.Fab")
		)
		(fp_line
			(start 0.8636 0.4572)
			(end 0.8636 0.4318)
			(stroke
				(width 0.1)
				(type default)
			)
			(layer "B.Fab")
		)
		(fp_line
			(start 0.8636 0.4318)
			(end 0.8636 0.4064)
			(stroke
				(width 0.1)
				(type default)
			)
			(layer "B.Fab")
		)
		(fp_line
			(start 0.8636 0.4064)
			(end 1.1938 0.4064)
			(stroke
				(width 0.1)
				(type default)
			)
			(layer "B.Fab")
		)
		(fp_line
			(start 0.8636 -0.406654)
			(end 0.8636 -0.4572)
			(stroke
				(width 0.1)
				(type default)
			)
			(layer "B.Fab")
		)
		(fp_line
			(start 0.8636 -0.4572)
			(end -0.8636 -0.4572)
			(stroke
				(width 0.1)
				(type default)
			)
			(layer "B.Fab")
		)
		(fp_line
			(start -0.8636 0.4572)
			(end 0.8636 0.4572)
			(stroke
				(width 0.1)
				(type default)
			)
			(layer "B.Fab")
		)
		(fp_line
			(start -0.8636 0.4064)
			(end -0.8636 0.4572)
			(stroke
				(width 0.1)
				(type default)
			)
			(layer "B.Fab")
		)
		(fp_line
			(start -0.8636 -0.406654)
			(end -1.1938 -0.406654)
			(stroke
				(width 0.1)
				(type default)
			)
			(layer "B.Fab")
		)
		(fp_line
			(start -0.8636 -0.4572)
			(end -0.8636 -0.406654)
			(stroke
				(width 0.1)
				(type default)
			)
			(layer "B.Fab")
		)
		(fp_line
			(start -1.1938 0.4064)
			(end -0.8636 0.4064)
			(stroke
				(width 0.1)
				(type default)
			)
			(layer "B.Fab")
		)
		(fp_line
			(start -1.1938 -0.406654)
			(end -1.1938 0.4064)
			(stroke
				(width 0.1)
				(type default)
			)
			(layer "B.Fab")
		)
		(pad "1" smd rect
			(at 0.7366 0 90)
			(size 0.7112 0.8128)
			(layers "B.Cu" "B.Mask" "B.Paste")
			(net "P3V3_AUX")
		)
		(pad "2" smd rect
			(at -0.7366 0 90)
			(size 0.7112 0.8128)
			(layers "B.Cu" "B.Mask" "B.Paste")
			(net "P3V3_AUX_FPGA_VCCIO3")
		)
	)
	(footprint ""
		(layer "B.Cu")
		(at 213.422484 -321.554856 -90)
		(property "Reference" "C77"
			(at 0 0 90)
			(layer "B.SilkS")
			(hide yes)
			(effects
				(font
					(size 1.27 1.27)
				)
				(justify mirror)
			)
		)
		(property "Value" ""
			(at 0 0 90)
			(layer "B.Fab")
			(effects
				(font
					(size 1.27 1.27)
				)
				(justify mirror)
			)
		)
		(duplicate_pad_numbers_are_jumpers no)
		(fp_line
			(start -1.524 0.762)
			(end 1.524 0.762)
			(stroke
				(width 0.1524)
				(type default)
			)
			(layer "B.SilkS")
		)
		(fp_line
			(start 1.524 0.762)
			(end 1.524 -0.762)
			(stroke
				(width 0.1524)
				(type default)
			)
			(layer "B.SilkS")
		)
		(fp_line
			(start -1.524 -0.762)
			(end -1.524 0.762)
			(stroke
				(width 0.1524)
				(type default)
			)
			(layer "B.SilkS")
		)
		(fp_line
			(start 1.524 -0.762)
			(end -1.524 -0.762)
			(stroke
				(width 0.1524)
				(type default)
			)
			(layer "B.SilkS")
		)
		(fp_line
			(start -1.1049 0.724916)
			(end -1.1049 -0.724916)
			(stroke
				(width 0.1)
				(type default)
			)
			(layer "B.Fab")
		)
		(fp_line
			(start 1.1049 0.724916)
			(end -1.1049 0.724916)
			(stroke
				(width 0.1)
				(type default)
			)
			(layer "B.Fab")
		)
		(fp_line
			(start -1.1049 -0.724916)
			(end 1.1049 -0.724916)
			(stroke
				(width 0.1)
				(type default)
			)
			(layer "B.Fab")
		)
		(fp_line
			(start 1.1049 -0.724916)
			(end 1.1049 0.724916)
			(stroke
				(width 0.1)
				(type default)
			)
			(layer "B.Fab")
		)
		(pad "1" smd rect
			(at 0.889 0 270)
			(size 1.016 1.27)
			(layers "B.Cu" "B.Mask" "B.Paste")
			(net "P12V_S3_AUX_CPU1_NVDIMM")
		)
		(pad "2" smd rect
			(at -0.889 0 270)
			(size 1.016 1.27)
			(layers "B.Cu" "B.Mask" "B.Paste")
			(net "GND")
		)
	)
	(footprint ""
		(layer "B.Cu")
		(at 313.78144 -193.53911 -90)
		(property "Reference" "R2"
			(at 0 0 90)
			(layer "B.SilkS")
			(hide yes)
			(effects
				(font
					(size 1.27 1.27)
				)
				(justify mirror)
			)
		)
		(property "Value" ""
			(at 0 0 90)
			(layer "B.Fab")
			(effects
				(font
					(size 1.27 1.27)
				)
				(justify mirror)
			)
		)
		(duplicate_pad_numbers_are_jumpers no)
		(fp_line
			(start -0.7874 0.4064)
			(end 0.7874 0.4064)
			(stroke
				(width 0.1524)
				(type default)
			)
			(layer "B.SilkS")
		)
		(fp_line
			(start 0.7874 0.4064)
			(end 0.7874 -0.4064)
			(stroke
				(width 0.1524)
				(type default)
			)
			(layer "B.SilkS")
		)
		(fp_line
			(start -0.7874 -0.4064)
			(end -0.7874 0.4064)
			(stroke
				(width 0.1524)
				(type default)
			)
			(layer "B.SilkS")
		)
		(fp_line
			(start 0.7874 -0.4064)
			(end -0.7874 -0.4064)
			(stroke
				(width 0.1524)
				(type default)
			)
			(layer "B.SilkS")
		)
		(fp_line
			(start -0.67945 0.3048)
			(end -0.120396 0.3048)
			(stroke
				(width 0.1)
				(type default)
			)
			(layer "B.Fab")
		)
		(fp_line
			(start -0.120396 0.3048)
			(end -0.120396 0.2794)
			(stroke
				(width 0.1)
				(type default)
			)
			(layer "B.Fab")
		)
		(fp_line
			(start 0.12065 0.3048)
			(end 0.67945 0.3048)
			(stroke
				(width 0.1)
				(type default)
			)
			(layer "B.Fab")
		)
		(fp_line
			(start 0.67945 0.3048)
			(end 0.67945 -0.305054)
			(stroke
				(width 0.1)
				(type default)
			)
			(layer "B.Fab")
		)
		(fp_line
			(start -0.120396 0.2794)
			(end 0.12065 0.2794)
			(stroke
				(width 0.1)
				(type default)
			)
			(layer "B.Fab")
		)
		(fp_line
			(start 0.12065 0.2794)
			(end 0.12065 0.3048)
			(stroke
				(width 0.1)
				(type default)
			)
			(layer "B.Fab")
		)
		(fp_line
			(start -0.12065 -0.2794)
			(end -0.12065 -0.3048)
			(stroke
				(width 0.1)
				(type default)
			)
			(layer "B.Fab")
		)
		(fp_line
			(start 0.12065 -0.2794)
			(end -0.12065 -0.2794)
			(stroke
				(width 0.1)
				(type default)
			)
			(layer "B.Fab")
		)
		(fp_line
			(start -0.67945 -0.3048)
			(end -0.67945 0.3048)
			(stroke
				(width 0.1)
				(type default)
			)
			(layer "B.Fab")
		)
		(fp_line
			(start -0.12065 -0.3048)
			(end -0.67945 -0.3048)
			(stroke
				(width 0.1)
				(type default)
			)
			(layer "B.Fab")
		)
		(fp_line
			(start 0.12065 -0.305054)
			(end 0.12065 -0.2794)
			(stroke
				(width 0.1)
				(type default)
			)
			(layer "B.Fab")
		)
		(fp_line
			(start 0.67945 -0.305054)
			(end 0.12065 -0.305054)
			(stroke
				(width 0.1)
				(type default)
			)
			(layer "B.Fab")
		)
		(pad "1" smd circle
			(at 0.40005 0 90)
			(size 0 0)
			(layers "B.Cu" "B.Mask" "B.Paste")
			(net "H_CPU_PREQ_QS_GTL_N")
		)
		(pad "2" smd circle
			(at -0.40005 0 90)
			(size 0 0)
			(layers "B.Cu" "B.Mask" "B.Paste")
			(net "H_CPU0_PREQ_QS_GTL_R_N")
		)
	)
	(footprint ""
		(layer "B.Cu")
		(at 265.406378 -318.697102)
		(property "Reference" "R33"
			(at 0 0 0)
			(layer "B.SilkS")
			(hide yes)
			(effects
				(font
					(size 1.27 1.27)
				)
				(justify mirror)
			)
		)
		(property "Value" ""
			(at 0 0 0)
			(layer "B.Fab")
			(effects
				(font
					(size 1.27 1.27)
				)
				(justify mirror)
			)
		)
		(duplicate_pad_numbers_are_jumpers no)
		(fp_line
			(start -0.7874 -0.4064)
			(end -0.7874 0.4064)
			(stroke
				(width 0.1524)
				(type default)
			)
			(layer "B.SilkS")
		)
		(fp_line
			(start -0.7874 0.4064)
			(end 0.7874 0.4064)
			(stroke
				(width 0.1524)
				(type default)
			)
			(layer "B.SilkS")
		)
		(fp_line
			(start 0.7874 -0.4064)
			(end -0.7874 -0.4064)
			(stroke
				(width 0.1524)
				(type default)
			)
			(layer "B.SilkS")
		)
		(fp_line
			(start 0.7874 0.4064)
			(end 0.7874 -0.4064)
			(stroke
				(width 0.1524)
				(type default)
			)
			(layer "B.SilkS")
		)
		(fp_line
			(start -0.67945 -0.3048)
			(end -0.67945 0.3048)
			(stroke
				(width 0.1)
				(type default)
			)
			(layer "B.Fab")
		)
		(fp_line
			(start -0.67945 0.3048)
			(end -0.120396 0.3048)
			(stroke
				(width 0.1)
				(type default)
			)
			(layer "B.Fab")
		)
		(fp_line
			(start -0.12065 -0.3048)
			(end -0.67945 -0.3048)
			(stroke
				(width 0.1)
				(type default)
			)
			(layer "B.Fab")
		)
		(fp_line
			(start -0.12065 -0.2794)
			(end -0.12065 -0.3048)
			(stroke
				(width 0.1)
				(type default)
			)
			(layer "B.Fab")
		)
		(fp_line
			(start -0.120396 0.2794)
			(end 0.12065 0.2794)
			(stroke
				(width 0.1)
				(type default)
			)
			(layer "B.Fab")
		)
		(fp_line
			(start -0.120396 0.3048)
			(end -0.120396 0.2794)
			(stroke
				(width 0.1)
				(type default)
			)
			(layer "B.Fab")
		)
		(fp_line
			(start 0.12065 -0.305054)
			(end 0.12065 -0.2794)
			(stroke
				(width 0.1)
				(type default)
			)
			(layer "B.Fab")
		)
		(fp_line
			(start 0.12065 -0.2794)
			(end -0.12065 -0.2794)
			(stroke
				(width 0.1)
				(type default)
			)
			(layer "B.Fab")
		)
		(fp_line
			(start 0.12065 0.2794)
			(end 0.12065 0.3048)
			(stroke
				(width 0.1)
				(type default)
			)
			(layer "B.Fab")
		)
		(fp_line
			(start 0.12065 0.3048)
			(end 0.67945 0.3048)
			(stroke
				(width 0.1)
				(type default)
			)
			(layer "B.Fab")
		)
		(fp_line
			(start 0.67945 -0.305054)
			(end 0.12065 -0.305054)
			(stroke
				(width 0.1)
				(type default)
			)
			(layer "B.Fab")
		)
		(fp_line
			(start 0.67945 0.3048)
			(end 0.67945 -0.305054)
			(stroke
				(width 0.1)
				(type default)
			)
			(layer "B.Fab")
		)
		(pad "1" smd circle
			(at 0.40005 0 180)
			(size 0 0)
			(layers "B.Cu" "B.Mask" "B.Paste")
			(net "PD_CHD_CPU0_DIMM2_SAA")
		)
		(pad "2" smd circle
			(at -0.40005 0 180)
			(size 0 0)
			(layers "B.Cu" "B.Mask" "B.Paste")
			(net "GND")
		)
	)
	(footprint ""
		(layer "B.Cu")
		(at 312.443622 -36.820348)
		(property "Reference" "R1656"
			(at 0 0 0)
			(layer "B.SilkS")
			(hide yes)
			(effects
				(font
					(size 1.27 1.27)
				)
				(justify mirror)
			)
		)
		(property "Value" ""
			(at 0 0 0)
			(layer "B.Fab")
			(effects
				(font
					(size 1.27 1.27)
				)
				(justify mirror)
			)
		)
		(duplicate_pad_numbers_are_jumpers no)
		(fp_line
			(start -0.7874 -0.4064)
			(end -0.7874 0.4064)
			(stroke
				(width 0.1524)
				(type default)
			)
			(layer "B.SilkS")
		)
		(fp_line
			(start -0.7874 0.4064)
			(end 0.7874 0.4064)
			(stroke
				(width 0.1524)
				(type default)
			)
			(layer "B.SilkS")
		)
		(fp_line
			(start 0.7874 -0.4064)
			(end -0.7874 -0.4064)
			(stroke
				(width 0.1524)
				(type default)
			)
			(layer "B.SilkS")
		)
		(fp_line
			(start 0.7874 0.4064)
			(end 0.7874 -0.4064)
			(stroke
				(width 0.1524)
				(type default)
			)
			(layer "B.SilkS")
		)
		(fp_line
			(start -0.67945 -0.3048)
			(end -0.67945 0.3048)
			(stroke
				(width 0.1)
				(type default)
			)
			(layer "B.Fab")
		)
		(fp_line
			(start -0.67945 0.3048)
			(end -0.120396 0.3048)
			(stroke
				(width 0.1)
				(type default)
			)
			(layer "B.Fab")
		)
		(fp_line
			(start -0.12065 -0.3048)
			(end -0.67945 -0.3048)
			(stroke
				(width 0.1)
				(type default)
			)
			(layer "B.Fab")
		)
		(fp_line
			(start -0.12065 -0.2794)
			(end -0.12065 -0.3048)
			(stroke
				(width 0.1)
				(type default)
			)
			(layer "B.Fab")
		)
		(fp_line
			(start -0.120396 0.2794)
			(end 0.12065 0.2794)
			(stroke
				(width 0.1)
				(type default)
			)
			(layer "B.Fab")
		)
		(fp_line
			(start -0.120396 0.3048)
			(end -0.120396 0.2794)
			(stroke
				(width 0.1)
				(type default)
			)
			(layer "B.Fab")
		)
		(fp_line
			(start 0.12065 -0.305054)
			(end 0.12065 -0.2794)
			(stroke
				(width 0.1)
				(type default)
			)
			(layer "B.Fab")
		)
		(fp_line
			(start 0.12065 -0.2794)
			(end -0.12065 -0.2794)
			(stroke
				(width 0.1)
				(type default)
			)
			(layer "B.Fab")
		)
		(fp_line
			(start 0.12065 0.2794)
			(end 0.12065 0.3048)
			(stroke
				(width 0.1)
				(type default)
			)
			(layer "B.Fab")
		)
		(fp_line
			(start 0.12065 0.3048)
			(end 0.67945 0.3048)
			(stroke
				(width 0.1)
				(type default)
			)
			(layer "B.Fab")
		)
		(fp_line
			(start 0.67945 -0.305054)
			(end 0.12065 -0.305054)
			(stroke
				(width 0.1)
				(type default)
			)
			(layer "B.Fab")
		)
		(fp_line
			(start 0.67945 0.3048)
			(end 0.67945 -0.305054)
			(stroke
				(width 0.1)
				(type default)
			)
			(layer "B.Fab")
		)
		(pad "1" smd circle
			(at 0.40005 0 180)
			(size 0 0)
			(layers "B.Cu" "B.Mask" "B.Paste")
			(net "IRQ_SML1_PMBUS_ALERT_N")
		)
		(pad "2" smd circle
			(at -0.40005 0 180)
			(size 0 0)
			(layers "B.Cu" "B.Mask" "B.Paste")
			(net "IRQ_SML1_PMBUS_PLD_ALERT_N")
		)
	)
	(footprint ""
		(layer "B.Cu")
		(at 74.85888 -11.267948 90)
		(property "Reference" "R3173"
			(at 0 0 90)
			(layer "B.SilkS")
			(hide yes)
			(effects
				(font
					(size 1.27 1.27)
				)
				(justify mirror)
			)
		)
		(property "Value" ""
			(at 0 0 90)
			(layer "B.Fab")
			(effects
				(font
					(size 1.27 1.27)
				)
				(justify mirror)
			)
		)
		(duplicate_pad_numbers_are_jumpers no)
		(fp_line
			(start 0.7874 -0.4064)
			(end -0.7874 -0.4064)
			(stroke
				(width 0.1524)
				(type default)
			)
			(layer "B.SilkS")
		)
		(fp_line
			(start -0.7874 -0.4064)
			(end -0.7874 0.4064)
			(stroke
				(width 0.1524)
				(type default)
			)
			(layer "B.SilkS")
		)
		(fp_line
			(start 0.7874 0.4064)
			(end 0.7874 -0.4064)
			(stroke
				(width 0.1524)
				(type default)
			)
			(layer "B.SilkS")
		)
		(fp_line
			(start -0.7874 0.4064)
			(end 0.7874 0.4064)
			(stroke
				(width 0.1524)
				(type default)
			)
			(layer "B.SilkS")
		)
		(fp_line
			(start 0.67945 -0.305054)
			(end 0.12065 -0.305054)
			(stroke
				(width 0.1)
				(type default)
			)
			(layer "B.Fab")
		)
		(fp_line
			(start 0.12065 -0.305054)
			(end 0.12065 -0.2794)
			(stroke
				(width 0.1)
				(type default)
			)
			(layer "B.Fab")
		)
		(fp_line
			(start -0.12065 -0.3048)
			(end -0.67945 -0.3048)
			(stroke
				(width 0.1)
				(type default)
			)
			(layer "B.Fab")
		)
		(fp_line
			(start -0.67945 -0.3048)
			(end -0.67945 0.3048)
			(stroke
				(width 0.1)
				(type default)
			)
			(layer "B.Fab")
		)
		(fp_line
			(start 0.12065 -0.2794)
			(end -0.12065 -0.2794)
			(stroke
				(width 0.1)
				(type default)
			)
			(layer "B.Fab")
		)
		(fp_line
			(start -0.12065 -0.2794)
			(end -0.12065 -0.3048)
			(stroke
				(width 0.1)
				(type default)
			)
			(layer "B.Fab")
		)
		(fp_line
			(start 0.12065 0.2794)
			(end 0.12065 0.3048)
			(stroke
				(width 0.1)
				(type default)
			)
			(layer "B.Fab")
		)
		(fp_line
			(start -0.120396 0.2794)
			(end 0.12065 0.2794)
			(stroke
				(width 0.1)
				(type default)
			)
			(layer "B.Fab")
		)
		(fp_line
			(start 0.67945 0.3048)
			(end 0.67945 -0.305054)
			(stroke
				(width 0.1)
				(type default)
			)
			(layer "B.Fab")
		)
		(fp_line
			(start 0.12065 0.3048)
			(end 0.67945 0.3048)
			(stroke
				(width 0.1)
				(type default)
			)
			(layer "B.Fab")
		)
		(fp_line
			(start -0.120396 0.3048)
			(end -0.120396 0.2794)
			(stroke
				(width 0.1)
				(type default)
			)
			(layer "B.Fab")
		)
		(fp_line
			(start -0.67945 0.3048)
			(end -0.120396 0.3048)
			(stroke
				(width 0.1)
				(type default)
			)
			(layer "B.Fab")
		)
		(pad "1" smd circle
			(at 0.40005 0 270)
			(size 0 0)
			(layers "B.Cu" "B.Mask" "B.Paste")
			(net "SGPIO_OCP_V3_2_LD_N")
		)
		(pad "2" smd circle
			(at -0.40005 0 270)
			(size 0 0)
			(layers "B.Cu" "B.Mask" "B.Paste")
			(net "P3V3_OCP_V3_2")
		)
	)
)
